# BASEBOARD_FAB2 (Tioga Pass) — schematic netlist excerpt (pin names and nets, part order shuffled) for the footprints in the layout excerpt that follows; sources: Cadence DE-HDL packaged netlist, KiCad conversion of Wiwynn_Tioga_Pass_MB.brd

R2N8  RES  665 1.0% CHIP  pkg 0402  page 138 : A = P3V3_STBY ; B = SMB_SMLINK0_STBY_LVC3_SDA

T1P19  TPAD-DIFF-4P-GP  pkg DISCRET-GB3  page 256
  \1\  = L1_100OHM_6INCH_DP
  \2\  = L1_100OHM_6INCH_DN
  GND1  = GND
  GND2  = GND

(kicad_pcb
	(version 20260206)
	(generator "pcbnew")
	(generator_version "10.0")
	(general
		(thickness 1.6)
		(legacy_teardrops no)
	)
	(paper "A4")
	(title_block
		(title "Wiwynn_Tioga_Pass_MB.brd")
		(comment 1 "Tioga Pass / footprints 1919-1920 of 4770")
	)
	(layers
		(0 "F.Cu" signal "TOP")
		(4 "In1.Cu" signal "L2GND")
		(6 "In2.Cu" signal "L3")
		(8 "In3.Cu" signal "L4GND")
		(10 "In4.Cu" signal "L5")
		(12 "In5.Cu" signal "L6GND")
		(14 "In6.Cu" signal "L7VCC")
		(16 "In7.Cu" signal "L8VCC")
		(18 "In8.Cu" signal "L9GND")
		(20 "In9.Cu" signal "L10")
		(22 "In10.Cu" signal "L11GND")
		(24 "In11.Cu" signal "L12")
		(26 "In12.Cu" signal "L13GND")
		(2 "B.Cu" signal "BOTTOM")
		(9 "F.Adhes" user "F.Adhesive")
		(11 "B.Adhes" user "B.Adhesive")
		(13 "F.Paste" user "Package Geometry/Pastemask Top")
		(15 "B.Paste" user "Package Geometry/Pastemask Bottom")
		(5 "F.SilkS" user "Ref Des/Silkscreen Top")
		(7 "B.SilkS" user "Ref Des/Silkscreen Bottom")
		(1 "F.Mask" user "Board Geometry/Soldermask Top")
		(3 "B.Mask" user "Board Geometry/Soldermask Bottom")
		(17 "Dwgs.User" user "User.Drawings")
		(19 "Cmts.User" user "User.Comments")
		(21 "Eco1.User" user "User.Eco1")
		(23 "Eco2.User" user "User.Eco2")
		(25 "Edge.Cuts" user "Board Geometry/Outline")
		(27 "Margin" user)
		(31 "F.CrtYd" user "Package Geometry/Place Bound Top")
		(29 "B.CrtYd" user "Package Geometry/Place Bound Bottom")
		(35 "F.Fab" user "Ref Des/Assembly Top")
		(33 "B.Fab" user "Ref Des/Assembly Bottom")
	)
	(footprint ""
		(layer "F.Cu")
		(at 352.363532 12.003278 -90)
		(property "Reference" "T1P19"
			(at 0 0 270)
			(layer "F.SilkS")
			(hide yes)
			(effects
				(font
					(size 1.27 1.27)
				)
			)
		)
		(property "Value" "*"
			(at -3.302 1.12395 270)
			(unlocked yes)
			(layer "F.Fab")
			(hide yes)
			(effects
				(font
					(size 0.889 0.889)
					(thickness 0.1524)
				)
			)
		)
		(property "Device Type" "TPAD-DIFF-4P-GP_DISCRET-GB3-TPA"
			(at -3.302 -0.40005 270)
			(unlocked yes)
			(layer "F.Fab")
			(hide yes)
			(effects
				(font
					(size 0.889 0.889)
					(thickness 0.1524)
				)
			)
		)
		(duplicate_pad_numbers_are_jumpers no)
		(fp_line
			(start -2.286 2.286)
			(end 2.286 2.286)
			(stroke
				(width 0.1524)
				(type default)
			)
			(layer "F.SilkS")
		)
		(fp_line
			(start 2.286 2.286)
			(end 2.286 -2.286)
			(stroke
				(width 0.1524)
				(type default)
			)
			(layer "F.SilkS")
		)
		(fp_line
			(start -2.286 -2.286)
			(end -2.286 2.286)
			(stroke
				(width 0.1524)
				(type default)
			)
			(layer "F.SilkS")
		)
		(fp_line
			(start 2.286 -2.286)
			(end -2.286 -2.286)
			(stroke
				(width 0.1524)
				(type default)
			)
			(layer "F.SilkS")
		)
		(fp_line
			(start -2.413 -2.413)
			(end -2.413 -1.143)
			(stroke
				(width 0.4064)
				(type default)
			)
			(layer "F.SilkS")
		)
		(fp_line
			(start -1.143 -2.413)
			(end -2.413 -2.413)
			(stroke
				(width 0.4064)
				(type default)
			)
			(layer "F.SilkS")
		)
		(fp_rect
			(start -2.54 2.54)
			(end 2.54 -2.54)
			(stroke
				(width 0)
				(type default)
			)
			(fill no)
			(layer "F.CrtYd")
		)
		(fp_rect
			(start -2.54 2.54)
			(end 2.54 -2.54)
			(stroke
				(width 0)
				(type default)
			)
			(fill no)
			(layer "F.Fab")
		)
		(pad "1" thru_hole circle
			(at -1.27 -1.27 270)
			(size 1.524 1.524)
			(drill 0.9144)
			(layers "*.Cu" "*.Mask")
			(remove_unused_layers no)
			(net "L1_100OHM_6INCH_DP")
			(clearance -0.0508)
			(thermal_gap 0.127)
			(padstack
				(mode front_inner_back)
				(layer "Inner"
					(shape circle)
					(size 1.1684 1.1684)
					(clearance 0.127)
				)
				(layer "B.Cu"
					(shape circle)
					(size 1.524 1.524)
					(clearance -0.0508)
				)
			)
		)
		(pad "2" thru_hole circle
			(at 1.27 -1.27 270)
			(size 1.524 1.524)
			(drill 0.9144)
			(layers "*.Cu" "*.Mask")
			(remove_unused_layers no)
			(net "L1_100OHM_6INCH_DN")
			(clearance -0.0508)
			(thermal_gap 0.127)
			(padstack
				(mode front_inner_back)
				(layer "Inner"
					(shape circle)
					(size 1.1684 1.1684)
					(clearance 0.127)
				)
				(layer "B.Cu"
					(shape circle)
					(size 1.524 1.524)
					(clearance -0.0508)
				)
			)
		)
		(pad "GND1" thru_hole rect
			(at -1.27 1.27 270)
			(size 1.524 1.524)
			(drill 0.9144)
			(layers "*.Cu" "*.Mask")
			(remove_unused_layers no)
			(net "GND")
			(clearance -0.0508)
			(thermal_gap 0.127)
			(padstack
				(mode front_inner_back)
				(layer "Inner"
					(shape circle)
					(size 1.1684 1.1684)
					(clearance 0.127)
				)
				(layer "B.Cu"
					(shape rect)
					(size 1.524 1.524)
					(clearance -0.0508)
				)
			)
		)
		(pad "GND2" thru_hole rect
			(at 1.27 1.27 270)
			(size 1.524 1.524)
			(drill 0.9144)
			(layers "*.Cu" "*.Mask")
			(remove_unused_layers no)
			(net "GND")
			(clearance -0.0508)
			(thermal_gap 0.127)
			(padstack
				(mode front_inner_back)
				(layer "Inner"
					(shape circle)
					(size 1.1684 1.1684)
					(clearance 0.127)
				)
				(layer "B.Cu"
					(shape rect)
					(size 1.524 1.524)
					(clearance -0.0508)
				)
			)
		)
	)
	(footprint ""
		(layer "F.Cu")
		(at 411.0355 -108.966 -90)
		(property "Reference" "R2N8"
			(at 0 0 270)
			(layer "F.SilkS")
			(hide yes)
			(effects
				(font
					(size 1.27 1.27)
				)
			)
		)
		(property "Value" ""
			(at 0 0 270)
			(layer "F.Fab")
			(effects
				(font
					(size 1.27 1.27)
				)
			)
		)
		(duplicate_pad_numbers_are_jumpers no)
		(fp_poly
			(pts
				(xy -0.2794 -0.1016) (xy 0.2794 -0.1016) (xy 0.2794 0.9906) (xy -0.2794 0.9906)
			)
			(stroke
				(width 0)
				(type default)
			)
			(fill no)
			(layer "F.CrtYd")
		)
		(fp_line
			(start -0.2794 0.9906)
			(end 0.2794 0.9906)
			(stroke
				(width 0.1)
				(type default)
			)
			(layer "F.Fab")
		)
		(fp_line
			(start 0.2794 0.9906)
			(end 0.2794 -0.1016)
			(stroke
				(width 0.1)
				(type default)
			)
			(layer "F.Fab")
		)
		(fp_line
			(start -0.2794 -0.1016)
			(end -0.2794 0.9906)
			(stroke
				(width 0.1)
				(type default)
			)
			(layer "F.Fab")
		)
		(fp_line
			(start 0.2794 -0.1016)
			(end -0.2794 -0.1016)
			(stroke
				(width 0.1)
				(type default)
			)
			(layer "F.Fab")
		)
		(pad "1" smd rect
			(at 0 0 270)
			(size 0.508 0.508)
			(layers "F.Cu" "F.Mask" "F.Paste")
			(net "P3V3_STBY")
		)
		(pad "2" smd rect
			(at 0 0.889 270)
			(size 0.508 0.508)
			(layers "F.Cu" "F.Mask" "F.Paste")
			(net "SMB_SMLINK0_STBY_LVC3_SDA")
		)
		(zone
			(layer "F.Cu")
			(hatch none 0.5)
			(connect_pads
				(clearance 0)
			)
			(min_thickness 0.25)
			(keepout
				(tracks not_allowed)
				(vias allowed)
				(pads allowed)
				(copperpour not_allowed)
				(footprints allowed)
			)
			(placement
				(enabled no)
				(sheetname "")
			)
			(fill
				(thermal_gap 0.5)
				(thermal_bridge_width 0.5)
				(island_removal_mode 0)
			)
			(polygon
				(pts
					(xy 410.4005 -109.22) (xy 410.4005 -108.712) (xy 410.7815 -108.712) (xy 410.7815 -109.22)
				)
			)
		)
		(zone
			(layer "F.Cu")
			(hatch none 0.5)
			(connect_pads
				(clearance 0)
			)
			(min_thickness 0.25)
			(keepout
				(tracks allowed)
				(vias not_allowed)
				(pads allowed)
				(copperpour not_allowed)
				(footprints allowed)
			)
			(placement
				(enabled no)
				(sheetname "")
			)
			(fill
				(thermal_gap 0.5)
				(thermal_bridge_width 0.5)
				(island_removal_mode 0)
			)
			(polygon
				(pts
					(xy 410.7815 -109.22) (xy 410.7815 -108.712) (xy 410.4005 -108.712) (xy 410.4005 -109.22)
				)
			)
		)
	)
)
